(kicad_pcb
	(version 20260206)
	(generator "pcbnew")
	(generator_version "10.0")
	(general
		(thickness 1.6)
		(legacy_teardrops no)
	)
	(paper "A4")
	(title_block
		(title "fcb — 12433-1M.1206WZS1330.brd")
		(comment 1 "Open Vault / Knox (Wiwynn) / footprints 481-486 of 495")
	)
	(layers
		(0 "F.Cu" signal "TOP")
		(4 "In1.Cu" signal "L2GND")
		(6 "In2.Cu" signal "L3VCC")
		(2 "B.Cu" signal "BOTTOM")
		(9 "F.Adhes" user "F.Adhesive")
		(11 "B.Adhes" user "B.Adhesive")
		(13 "F.Paste" user "Package Geometry/Pastemask Top")
		(15 "B.Paste" user "Package Geometry/Pastemask Bottom")
		(5 "F.SilkS" user "Ref Des/Silkscreen Top")
		(7 "B.SilkS" user "Ref Des/Silkscreen Bottom")
		(1 "F.Mask" user "Board Geometry/Soldermask Top")
		(3 "B.Mask" user "Board Geometry/Soldermask Bottom")
		(17 "Dwgs.User" user "User.Drawings")
		(19 "Cmts.User" user "User.Comments")
		(21 "Eco1.User" user "User.Eco1")
		(23 "Eco2.User" user "User.Eco2")
		(25 "Edge.Cuts" user "Board Geometry/Outline")
		(27 "Margin" user)
		(31 "F.CrtYd" user "Package Geometry/Place Bound Top")
		(29 "B.CrtYd" user "Package Geometry/Place Bound Bottom")
		(35 "F.Fab" user "Ref Des/Assembly Top")
		(33 "B.Fab" user "Ref Des/Assembly Bottom")
	)
	(footprint ""
		(layer "F.Cu")
		(at 28.1686 -224.3074)
		(property "Reference" "R140"
			(at 0 0 0)
			(layer "F.SilkS")
			(hide yes)
			(effects
				(font
					(size 1.27 1.27)
				)
			)
		)
		(property "Value" "0R2J-2-GP"
			(at 0.064008 -3.993896 0)
			(unlocked yes)
			(layer "F.Fab")
			(hide yes)
			(effects
				(font
					(size 1.016 1.016)
					(thickness 0.1524)
				)
			)
		)
		(property "Device Type" "R402H16"
			(at 0.064008 -5.517896 0)
			(unlocked yes)
			(layer "F.Fab")
			(hide yes)
			(effects
				(font
					(size 1.016 1.016)
					(thickness 0.1524)
				)
			)
		)
		(duplicate_pad_numbers_are_jumpers no)
		(fp_line
			(start -0.508 -0.9398)
			(end -0.508 0.9398)
			(stroke
				(width 0.1524)
				(type default)
			)
			(layer "F.SilkS")
		)
		(fp_line
			(start 0.508 -0.9398)
			(end -0.508 -0.9398)
			(stroke
				(width 0.1524)
				(type default)
			)
			(layer "F.SilkS")
		)
		(fp_rect
			(start -0.508 0.9398)
			(end 0.508 -0.9398)
			(stroke
				(width 0)
				(type default)
			)
			(fill no)
			(layer "F.CrtYd")
		)
		(fp_rect
			(start -0.508 0.9398)
			(end 0.508 -0.9398)
			(stroke
				(width 0)
				(type default)
			)
			(fill no)
			(layer "F.Fab")
		)
		(pad "1" smd custom
			(at 0 -0.4445)
			(size 0.1397 0.1397)
			(layers "F.Cu" "F.Mask" "F.Paste")
			(net "PWM_OUT_FAN2_NET")
			(options
				(clearance outline)
				(anchor circle)
			)
			(primitives
				(gr_poly
					(pts
						(arc
							(start -0.1778 -0.2794)
							(mid -0.249642 -0.249642)
							(end -0.2794 -0.1778)
						)
						(arc
							(start -0.2794 0.1778)
							(mid -0.249642 0.249642)
							(end -0.1778 0.2794)
						)
						(arc
							(start 0.1778 0.2794)
							(mid 0.249642 0.249642)
							(end 0.2794 0.1778)
						)
						(arc
							(start 0.2794 -0.1778)
							(mid 0.249642 -0.249642)
							(end 0.1778 -0.2794)
						)
					)
					(width 0)
					(fill yes)
				)
			)
		)
		(pad "2" smd custom
			(at 0 0.4445)
			(size 0.1397 0.1397)
			(layers "F.Cu" "F.Mask" "F.Paste")
			(net "PWM_OUT_FAN2")
			(options
				(clearance outline)
				(anchor circle)
			)
			(primitives
				(gr_poly
					(pts
						(arc
							(start -0.1778 -0.2794)
							(mid -0.249642 -0.249642)
							(end -0.2794 -0.1778)
						)
						(arc
							(start -0.2794 0.1778)
							(mid -0.249642 0.249642)
							(end -0.1778 0.2794)
						)
						(arc
							(start 0.1778 0.2794)
							(mid 0.249642 0.249642)
							(end 0.2794 0.1778)
						)
						(arc
							(start 0.2794 -0.1778)
							(mid 0.249642 -0.249642)
							(end 0.1778 -0.2794)
						)
					)
					(width 0)
					(fill yes)
				)
			)
		)
	)
	(footprint ""
		(layer "F.Cu")
		(at 37.211 -378.333 180)
		(property "Reference" "PR27"
			(at 0 0 180)
			(layer "F.SilkS")
			(hide yes)
			(effects
				(font
					(size 1.27 1.27)
				)
			)
		)
		(property "Value" "10R2F-L-GP"
			(at 0.064008 -3.993896 180)
			(unlocked yes)
			(layer "F.Fab")
			(hide yes)
			(effects
				(font
					(size 1.016 1.016)
					(thickness 0.1524)
				)
			)
		)
		(property "Device Type" "R402H14"
			(at 0.064008 -5.517896 180)
			(unlocked yes)
			(layer "F.Fab")
			(hide yes)
			(effects
				(font
					(size 1.016 1.016)
					(thickness 0.1524)
				)
			)
		)
		(duplicate_pad_numbers_are_jumpers no)
		(fp_line
			(start 0.508 -0.9398)
			(end -0.508 -0.9398)
			(stroke
				(width 0.1524)
				(type default)
			)
			(layer "F.SilkS")
		)
		(fp_line
			(start -0.508 -0.9398)
			(end -0.508 0.9398)
			(stroke
				(width 0.1524)
				(type default)
			)
			(layer "F.SilkS")
		)
		(fp_rect
			(start -0.508 0.9398)
			(end 0.508 -0.9398)
			(stroke
				(width 0)
				(type default)
			)
			(fill no)
			(layer "F.CrtYd")
		)
		(fp_rect
			(start -0.508 0.9398)
			(end 0.508 -0.9398)
			(stroke
				(width 0)
				(type default)
			)
			(fill no)
			(layer "F.Fab")
		)
		(pad "1" smd custom
			(at 0 -0.4445 180)
			(size 0.1397 0.1397)
			(layers "F.Cu" "F.Mask" "F.Paste")
			(net "ADM1276_GATE")
			(options
				(clearance outline)
				(anchor circle)
			)
			(primitives
				(gr_poly
					(pts
						(arc
							(start -0.1778 -0.2794)
							(mid -0.249642 -0.249642)
							(end -0.2794 -0.1778)
						)
						(arc
							(start -0.2794 0.1778)
							(mid -0.249642 0.249642)
							(end -0.1778 0.2794)
						)
						(arc
							(start 0.1778 0.2794)
							(mid 0.249642 0.249642)
							(end 0.2794 0.1778)
						)
						(arc
							(start 0.2794 -0.1778)
							(mid 0.249642 -0.249642)
							(end 0.1778 -0.2794)
						)
					)
					(width 0)
					(fill yes)
				)
			)
		)
		(pad "2" smd custom
			(at 0 0.4445 180)
			(size 0.1397 0.1397)
			(layers "F.Cu" "F.Mask" "F.Paste")
			(net "ADM1276_GATE_DRV2")
			(options
				(clearance outline)
				(anchor circle)
			)
			(primitives
				(gr_poly
					(pts
						(arc
							(start -0.1778 -0.2794)
							(mid -0.249642 -0.249642)
							(end -0.2794 -0.1778)
						)
						(arc
							(start -0.2794 0.1778)
							(mid -0.249642 0.249642)
							(end -0.1778 0.2794)
						)
						(arc
							(start 0.1778 0.2794)
							(mid 0.249642 0.249642)
							(end 0.2794 0.1778)
						)
						(arc
							(start 0.2794 -0.1778)
							(mid 0.249642 -0.249642)
							(end 0.1778 -0.2794)
						)
					)
					(width 0)
					(fill yes)
				)
			)
		)
	)
	(footprint ""
		(layer "F.Cu")
		(at 18.288 -122.555)
		(property "Reference" "PR60"
			(at 0 0 0)
			(layer "F.SilkS")
			(hide yes)
			(effects
				(font
					(size 1.27 1.27)
				)
			)
		)
		(property "Value" "D002R2512F-GP"
			(at -3.228594 -1.194054 0)
			(unlocked yes)
			(layer "F.Fab")
			(hide yes)
			(effects
				(font
					(size 1.016 1.016)
					(thickness 0.1524)
				)
			)
		)
		(property "Device Type" "R2512-2H32"
			(at -3.228594 -2.718054 0)
			(unlocked yes)
			(layer "F.Fab")
			(hide yes)
			(effects
				(font
					(size 1.016 1.016)
					(thickness 0.1524)
				)
			)
		)
		(duplicate_pad_numbers_are_jumpers no)
		(fp_line
			(start -1.9685 -3.81)
			(end 1.9685 -3.81)
			(stroke
				(width 0.1524)
				(type default)
			)
			(layer "F.SilkS")
		)
		(fp_line
			(start -1.9685 3.81)
			(end -1.9685 -3.81)
			(stroke
				(width 0.1524)
				(type default)
			)
			(layer "F.SilkS")
		)
		(fp_line
			(start 1.9685 -3.81)
			(end 1.9685 3.81)
			(stroke
				(width 0.1524)
				(type default)
			)
			(layer "F.SilkS")
		)
		(fp_line
			(start 1.9685 3.81)
			(end -1.9685 3.81)
			(stroke
				(width 0.1524)
				(type default)
			)
			(layer "F.SilkS")
		)
		(fp_rect
			(start -1.5875 3.175)
			(end 1.5875 -3.175)
			(stroke
				(width 0)
				(type default)
			)
			(fill no)
			(layer "F.CrtYd")
		)
		(fp_poly
			(pts
				(xy -2.2225 3.8862) (xy -2.2225 0.00254) (xy -1.5875 0.00254) (xy -1.5875 3.175) (xy 1.5875 3.175)
				(xy 1.5875 -3.175) (xy -1.5875 -3.175) (xy -1.5875 -0.00254) (xy -2.2225 -0.00254) (xy -2.2225 -3.8862)
				(xy 2.2225 -3.8862) (xy 2.2225 3.8862)
			)
			(stroke
				(width 0)
				(type default)
			)
			(fill no)
			(layer "F.CrtYd")
		)
		(fp_rect
			(start -2.2225 3.8862)
			(end 2.2225 -3.8862)
			(stroke
				(width 0)
				(type default)
			)
			(fill no)
			(layer "F.Fab")
		)
		(pad "1" smd rect
			(at 0 -2.273808)
			(size 3.429 2.5654)
			(layers "F.Cu" "F.Mask" "F.Paste")
			(net "P12V")
		)
		(pad "2" smd rect
			(at 0 2.273808)
			(size 3.429 2.5654)
			(layers "F.Cu" "F.Mask" "F.Paste")
			(net "P12VU_NET")
		)
	)
	(footprint ""
		(layer "F.Cu")
		(at 19.939 -18.161 90)
		(property "Reference" "R71"
			(at 0 0 90)
			(layer "F.SilkS")
			(hide yes)
			(effects
				(font
					(size 1.27 1.27)
				)
			)
		)
		(property "Value" "27KR3F-GP"
			(at -0.0254 -2.5146 90)
			(unlocked yes)
			(layer "F.Fab")
			(hide yes)
			(effects
				(font
					(size 1.016 1.016)
					(thickness 0.1524)
				)
			)
		)
		(property "Device Type" "R603H22"
			(at -0.0254 -4.0386 90)
			(unlocked yes)
			(layer "F.Fab")
			(hide yes)
			(effects
				(font
					(size 1.016 1.016)
					(thickness 0.1524)
				)
			)
		)
		(duplicate_pad_numbers_are_jumpers no)
		(fp_line
			(start 0.2032 0)
			(end 0.4826 0)
			(stroke
				(width 0.2032)
				(type default)
			)
			(layer "F.SilkS")
		)
		(fp_line
			(start -0.4826 0)
			(end -0.2032 0)
			(stroke
				(width 0.2032)
				(type default)
			)
			(layer "F.SilkS")
		)
		(fp_rect
			(start -0.5842 1.3335)
			(end 0.5842 -1.3335)
			(stroke
				(width 0)
				(type default)
			)
			(fill no)
			(layer "F.CrtYd")
		)
		(fp_rect
			(start -0.5842 1.3335)
			(end 0.5842 -1.3335)
			(stroke
				(width 0)
				(type default)
			)
			(fill no)
			(layer "F.Fab")
		)
		(pad "1" smd custom
			(at 0 -0.762 90)
			(size 0.2159 0.2159)
			(layers "F.Cu" "F.Mask" "F.Paste")
			(net "FAN_TACH12")
			(options
				(clearance outline)
				(anchor circle)
			)
			(primitives
				(gr_poly
					(pts
						(arc
							(start -0.3302 -0.4318)
							(mid -0.402042 -0.402042)
							(end -0.4318 -0.3302)
						)
						(arc
							(start -0.4318 0.3302)
							(mid -0.402042 0.402042)
							(end -0.3302 0.4318)
						)
						(arc
							(start 0.3302 0.4318)
							(mid 0.402042 0.402042)
							(end 0.4318 0.3302)
						)
						(arc
							(start 0.4318 -0.3302)
							(mid 0.402042 -0.402042)
							(end 0.3302 -0.4318)
						)
					)
					(width 0)
					(fill yes)
				)
			)
		)
		(pad "2" smd custom
			(at 0 0.762 90)
			(size 0.2159 0.2159)
			(layers "F.Cu" "F.Mask" "F.Paste")
			(net "FANIN_12")
			(options
				(clearance outline)
				(anchor circle)
			)
			(primitives
				(gr_poly
					(pts
						(arc
							(start -0.3302 -0.4318)
							(mid -0.402042 -0.402042)
							(end -0.4318 -0.3302)
						)
						(arc
							(start -0.4318 0.3302)
							(mid -0.402042 0.402042)
							(end -0.3302 0.4318)
						)
						(arc
							(start 0.3302 0.4318)
							(mid 0.402042 0.402042)
							(end 0.4318 0.3302)
						)
						(arc
							(start 0.4318 -0.3302)
							(mid 0.402042 -0.402042)
							(end 0.3302 -0.4318)
						)
					)
					(width 0)
					(fill yes)
				)
			)
		)
	)
	(footprint ""
		(layer "F.Cu")
		(at 22.860762 -15.621508 90)
		(property "Reference" "R77"
			(at 0 0 90)
			(layer "F.SilkS")
			(hide yes)
			(effects
				(font
					(size 1.27 1.27)
				)
			)
		)
		(property "Value" "10KR2F-2-GP"
			(at 0.064008 -3.993896 90)
			(unlocked yes)
			(layer "F.Fab")
			(hide yes)
			(effects
				(font
					(size 1.016 1.016)
					(thickness 0.1524)
				)
			)
		)
		(property "Device Type" "R402H16"
			(at 0.064008 -5.517896 90)
			(unlocked yes)
			(layer "F.Fab")
			(hide yes)
			(effects
				(font
					(size 1.016 1.016)
					(thickness 0.1524)
				)
			)
		)
		(duplicate_pad_numbers_are_jumpers no)
		(fp_line
			(start 0.508 -0.9398)
			(end -0.508 -0.9398)
			(stroke
				(width 0.1524)
				(type default)
			)
			(layer "F.SilkS")
		)
		(fp_line
			(start -0.508 -0.9398)
			(end -0.508 0.9398)
			(stroke
				(width 0.1524)
				(type default)
			)
			(layer "F.SilkS")
		)
		(fp_rect
			(start -0.508 0.9398)
			(end 0.508 -0.9398)
			(stroke
				(width 0)
				(type default)
			)
			(fill no)
			(layer "F.CrtYd")
		)
		(fp_rect
			(start -0.508 0.9398)
			(end 0.508 -0.9398)
			(stroke
				(width 0)
				(type default)
			)
			(fill no)
			(layer "F.Fab")
		)
		(pad "1" smd custom
			(at 0 -0.4445 90)
			(size 0.1397 0.1397)
			(layers "F.Cu" "F.Mask" "F.Paste")
			(net "FANIN_11")
			(options
				(clearance outline)
				(anchor circle)
			)
			(primitives
				(gr_poly
					(pts
						(arc
							(start -0.1778 -0.2794)
							(mid -0.249642 -0.249642)
							(end -0.2794 -0.1778)
						)
						(arc
							(start -0.2794 0.1778)
							(mid -0.249642 0.249642)
							(end -0.1778 0.2794)
						)
						(arc
							(start 0.1778 0.2794)
							(mid 0.249642 0.249642)
							(end 0.2794 0.1778)
						)
						(arc
							(start 0.2794 -0.1778)
							(mid 0.249642 -0.249642)
							(end 0.1778 -0.2794)
						)
					)
					(width 0)
					(fill yes)
				)
			)
		)
		(pad "2" smd custom
			(at 0 0.4445 90)
			(size 0.1397 0.1397)
			(layers "F.Cu" "F.Mask" "F.Paste")
			(net "GND")
			(options
				(clearance outline)
				(anchor circle)
			)
			(primitives
				(gr_poly
					(pts
						(arc
							(start -0.1778 -0.2794)
							(mid -0.249642 -0.249642)
							(end -0.2794 -0.1778)
						)
						(arc
							(start -0.2794 0.1778)
							(mid -0.249642 0.249642)
							(end -0.1778 0.2794)
						)
						(arc
							(start 0.1778 0.2794)
							(mid 0.249642 0.249642)
							(end 0.2794 0.1778)
						)
						(arc
							(start 0.2794 -0.1778)
							(mid 0.249642 -0.249642)
							(end 0.1778 -0.2794)
						)
					)
					(width 0)
					(fill yes)
				)
			)
		)
	)
	(footprint ""
		(layer "F.Cu")
		(at 5.5118 -420.9034 90)
		(property "Reference" "R126"
			(at 0 0 90)
			(layer "F.SilkS")
			(hide yes)
			(effects
				(font
					(size 1.27 1.27)
				)
			)
		)
		(property "Value" "1K8R6J-GP"
			(at -0.0508 -4.8514 90)
			(unlocked yes)
			(layer "F.Fab")
			(hide yes)
			(effects
				(font
					(size 1.016 1.016)
					(thickness 0.1524)
				)
			)
		)
		(property "Device Type" "R1206H28"
			(at 0 -6.3754 90)
			(unlocked yes)
			(layer "F.Fab")
			(hide yes)
			(effects
				(font
					(size 1.016 1.016)
					(thickness 0.1524)
				)
			)
		)
		(duplicate_pad_numbers_are_jumpers no)
		(fp_line
			(start 1.016 -2.2352)
			(end 1.016 2.2352)
			(stroke
				(width 0.1524)
				(type default)
			)
			(layer "F.SilkS")
		)
		(fp_line
			(start -1.016 -2.2352)
			(end 1.016 -2.2352)
			(stroke
				(width 0.1524)
				(type default)
			)
			(layer "F.SilkS")
		)
		(fp_line
			(start 1.016 2.2352)
			(end -1.016 2.2352)
			(stroke
				(width 0.1524)
				(type default)
			)
			(layer "F.SilkS")
		)
		(fp_line
			(start -1.016 2.2352)
			(end -1.016 -2.2352)
			(stroke
				(width 0.1524)
				(type default)
			)
			(layer "F.SilkS")
		)
		(fp_rect
			(start -1.0922 2.3114)
			(end 1.0922 -2.3114)
			(stroke
				(width 0)
				(type default)
			)
			(fill no)
			(layer "F.CrtYd")
		)
		(fp_poly
			(pts
				(xy -1.0922 -2.3114) (xy 1.0922 -2.3114) (xy 1.0922 2.3114) (xy -1.0922 2.3114)
			)
			(stroke
				(width 0)
				(type default)
			)
			(fill no)
			(layer "F.Fab")
		)
		(pad "1" smd rect
			(at 0 -1.397 90)
			(size 1.651 1.27)
			(layers "F.Cu" "F.Mask" "F.Paste")
			(net "P12V")
		)
		(pad "2" smd rect
			(at 0 1.397 90)
			(size 1.651 1.27)
			(layers "F.Cu" "F.Mask" "F.Paste")
			(net "LED_DR_LED1_BLUE")
		)
	)
)
